(kicad_pcb
	(version 20260206)
	(generator "pcbnew")
	(generator_version "10.0")
	(general
		(thickness 1.6)
		(legacy_teardrops no)
	)
	(paper "A4")
	(title_block
		(title "01162023_DA0F0TEBIF0_F0T_Expander_BD_F_brd_V02_OCP.brd")
		(comment 1 "Grand Teton / footprints 2073-2078 of 9728")
	)
	(layers
		(0 "F.Cu" signal "TOP")
		(4 "In1.Cu" signal "GND")
		(6 "In2.Cu" signal "VCC")
		(8 "In3.Cu" signal "VCC1")
		(10 "In4.Cu" signal "GND1")
		(12 "In5.Cu" signal "IN1")
		(14 "In6.Cu" signal "GND2")
		(16 "In7.Cu" signal "IN2")
		(18 "In8.Cu" signal "GND3")
		(20 "In9.Cu" signal "IN3")
		(22 "In10.Cu" signal "GND4")
		(24 "In11.Cu" signal "IN4")
		(26 "In12.Cu" signal "GND5")
		(28 "In13.Cu" signal "IN5")
		(30 "In14.Cu" signal "GND6")
		(32 "In15.Cu" signal "IN6")
		(34 "In16.Cu" signal "GND7")
		(2 "B.Cu" signal "BOTTOM")
		(9 "F.Adhes" user "F.Adhesive")
		(11 "B.Adhes" user "B.Adhesive")
		(13 "F.Paste" user "Package Geometry/Pastemask Top")
		(15 "B.Paste" user "Package Geometry/Pastemask Bottom")
		(5 "F.SilkS" user "Ref Des/Silkscreen Top")
		(7 "B.SilkS" user "Ref Des/Silkscreen Bottom")
		(1 "F.Mask" user "Board Geometry/Soldermask Top")
		(3 "B.Mask" user "Board Geometry/Soldermask Bottom")
		(17 "Dwgs.User" user "User.Drawings")
		(19 "Cmts.User" user "User.Comments")
		(21 "Eco1.User" user "User.Eco1")
		(23 "Eco2.User" user "User.Eco2")
		(25 "Edge.Cuts" user "Board Geometry/Outline")
		(27 "Margin" user)
		(31 "F.CrtYd" user "Package Geometry/Place Bound Top")
		(29 "B.CrtYd" user "Package Geometry/Place Bound Bottom")
		(35 "F.Fab" user "Ref Des/Assembly Top")
		(33 "B.Fab" user "Ref Des/Assembly Bottom")
	)
	(footprint ""
		(layer "F.Cu")
		(at 374.169432 -6.38683)
		(property "Reference" "U417"
			(at -1.246632 3.3401 0)
			(unlocked yes)
			(layer "F.SilkS")
			(effects
				(font
					(size 0.7874 0.5842)
					(thickness 0.1524)
				)
				(justify left)
			)
		)
		(property "Value" ""
			(at 0 0 0)
			(layer "F.Fab")
			(effects
				(font
					(size 1.27 1.27)
				)
			)
		)
		(duplicate_pad_numbers_are_jumpers no)
		(fp_line
			(start -3.447796 -2.500122)
			(end -3.447796 2.500122)
			(stroke
				(width 0.1524)
				(type default)
			)
			(layer "F.SilkS")
		)
		(fp_line
			(start -3.447796 2.500122)
			(end 3.447796 2.500122)
			(stroke
				(width 0.1524)
				(type default)
			)
			(layer "F.SilkS")
		)
		(fp_line
			(start -1.484122 -2.500122)
			(end -3.447796 -2.500122)
			(stroke
				(width 0.1524)
				(type default)
			)
			(layer "F.SilkS")
		)
		(fp_line
			(start 0 -1.016)
			(end -1.484122 -2.500122)
			(stroke
				(width 0.1524)
				(type default)
			)
			(layer "F.SilkS")
		)
		(fp_line
			(start 1.484122 -2.500122)
			(end 0 -1.016)
			(stroke
				(width 0.1524)
				(type default)
			)
			(layer "F.SilkS")
		)
		(fp_line
			(start 3.447796 -2.500122)
			(end 1.484122 -2.500122)
			(stroke
				(width 0.1524)
				(type default)
			)
			(layer "F.SilkS")
		)
		(fp_line
			(start 3.447796 2.500122)
			(end 3.447796 -2.500122)
			(stroke
				(width 0.1524)
				(type default)
			)
			(layer "F.SilkS")
		)
		(fp_poly
			(pts
				(xy -3.991356 -3.090672) (xy -4.709922 -2.372106) (xy -3.6322 -2.01295)
			)
			(stroke
				(width 0)
				(type default)
			)
			(fill yes)
			(layer "F.SilkS")
		)
		(fp_line
			(start -1.999996 -2.500122)
			(end -1.999996 2.500122)
			(stroke
				(width 0.1)
				(type default)
			)
			(layer "F.Fab")
		)
		(fp_line
			(start -1.999996 2.500122)
			(end 1.999996 2.500122)
			(stroke
				(width 0.1)
				(type default)
			)
			(layer "F.Fab")
		)
		(fp_line
			(start 1.999996 -2.500122)
			(end -1.999996 -2.500122)
			(stroke
				(width 0.1)
				(type default)
			)
			(layer "F.Fab")
		)
		(fp_line
			(start 1.999996 2.500122)
			(end 1.999996 -2.500122)
			(stroke
				(width 0.1)
				(type default)
			)
			(layer "F.Fab")
		)
		(fp_poly
			(pts
				(xy -4.5974 -2.413) (xy -4.5974 -1.397) (xy -3.5814 -1.905)
			)
			(stroke
				(width 0)
				(type default)
			)
			(fill yes)
			(layer "F.Fab")
		)
		(pad "1" smd rect
			(at -2.649982 -1.905 270)
			(size 0.6096 1.3208)
			(layers "F.Cu" "F.Mask" "F.Paste")
			(net "SMB_LM75_3_SDA")
		)
		(pad "2" smd rect
			(at -2.649982 -0.635 270)
			(size 0.6096 1.3208)
			(layers "F.Cu" "F.Mask" "F.Paste")
			(net "SMB_LM75_3_SCL")
		)
		(pad "3" smd rect
			(at -2.649982 0.635 270)
			(size 0.6096 1.3208)
			(layers "F.Cu" "F.Mask" "F.Paste")
			(net "Net_407")
		)
		(pad "4" smd rect
			(at -2.649982 1.905 270)
			(size 0.6096 1.3208)
			(layers "F.Cu" "F.Mask" "F.Paste")
			(net "GND")
		)
		(pad "5" smd rect
			(at 2.649982 1.905 270)
			(size 0.6096 1.3208)
			(layers "F.Cu" "F.Mask" "F.Paste")
			(net "LM75_3_A2")
		)
		(pad "6" smd rect
			(at 2.649982 0.635 270)
			(size 0.6096 1.3208)
			(layers "F.Cu" "F.Mask" "F.Paste")
			(net "LM75_3_A1")
		)
		(pad "7" smd rect
			(at 2.649982 -0.635 270)
			(size 0.6096 1.3208)
			(layers "F.Cu" "F.Mask" "F.Paste")
			(net "LM75_3_A0")
		)
		(pad "8" smd rect
			(at 2.649982 -1.905 270)
			(size 0.6096 1.3208)
			(layers "F.Cu" "F.Mask" "F.Paste")
			(net "P3V3_AUX")
		)
	)
	(footprint ""
		(layer "F.Cu")
		(at 126.897892 -308.470554 -90)
		(property "Reference" "C4247"
			(at 0 0 270)
			(layer "F.SilkS")
			(hide yes)
			(effects
				(font
					(size 1.27 1.27)
				)
			)
		)
		(property "Value" ""
			(at 0 0 270)
			(layer "F.Fab")
			(effects
				(font
					(size 1.27 1.27)
				)
			)
		)
		(duplicate_pad_numbers_are_jumpers no)
		(fp_line
			(start -1.2954 0.5842)
			(end -1.2954 -0.5842)
			(stroke
				(width 0.1524)
				(type default)
			)
			(layer "F.SilkS")
		)
		(fp_line
			(start 1.2954 0.5842)
			(end -1.2954 0.5842)
			(stroke
				(width 0.1524)
				(type default)
			)
			(layer "F.SilkS")
		)
		(fp_line
			(start -1.2954 -0.5842)
			(end 1.2954 -0.5842)
			(stroke
				(width 0.1524)
				(type default)
			)
			(layer "F.SilkS")
		)
		(fp_line
			(start 1.2954 -0.5842)
			(end 1.2954 0.5842)
			(stroke
				(width 0.1524)
				(type default)
			)
			(layer "F.SilkS")
		)
		(fp_line
			(start -0.8636 0.4572)
			(end -0.8636 0.4064)
			(stroke
				(width 0.1)
				(type default)
			)
			(layer "F.Fab")
		)
		(fp_line
			(start 0.8636 0.4572)
			(end -0.8636 0.4572)
			(stroke
				(width 0.1)
				(type default)
			)
			(layer "F.Fab")
		)
		(fp_line
			(start -1.1938 0.4064)
			(end -1.1938 -0.4064)
			(stroke
				(width 0.1)
				(type default)
			)
			(layer "F.Fab")
		)
		(fp_line
			(start -0.8636 0.4064)
			(end -1.1938 0.4064)
			(stroke
				(width 0.1)
				(type default)
			)
			(layer "F.Fab")
		)
		(fp_line
			(start 0.8636 0.4064)
			(end 0.8636 0.4572)
			(stroke
				(width 0.1)
				(type default)
			)
			(layer "F.Fab")
		)
		(fp_line
			(start 1.1938 0.4064)
			(end 0.8636 0.4064)
			(stroke
				(width 0.1)
				(type default)
			)
			(layer "F.Fab")
		)
		(fp_line
			(start -1.1938 -0.4064)
			(end -0.8636 -0.4064)
			(stroke
				(width 0.1)
				(type default)
			)
			(layer "F.Fab")
		)
		(fp_line
			(start -0.8636 -0.4064)
			(end -0.8636 -0.4572)
			(stroke
				(width 0.1)
				(type default)
			)
			(layer "F.Fab")
		)
		(fp_line
			(start 0.8636 -0.4064)
			(end 1.1938 -0.4064)
			(stroke
				(width 0.1)
				(type default)
			)
			(layer "F.Fab")
		)
		(fp_line
			(start 1.1938 -0.4064)
			(end 1.1938 0.4064)
			(stroke
				(width 0.1)
				(type default)
			)
			(layer "F.Fab")
		)
		(fp_line
			(start -0.8636 -0.4572)
			(end 0.8636 -0.4572)
			(stroke
				(width 0.1)
				(type default)
			)
			(layer "F.Fab")
		)
		(fp_line
			(start 0.8636 -0.4572)
			(end 0.8636 -0.4064)
			(stroke
				(width 0.1)
				(type default)
			)
			(layer "F.Fab")
		)
		(pad "1" smd rect
			(at -0.7366 0 180)
			(size 0.7112 0.8128)
			(layers "F.Cu" "F.Mask" "F.Paste")
			(net "P0V8_PEX1")
		)
		(pad "2" smd rect
			(at 0.7366 0 180)
			(size 0.7112 0.8128)
			(layers "F.Cu" "F.Mask" "F.Paste")
			(net "GND")
		)
	)
	(footprint ""
		(layer "F.Cu")
		(at 28.875228 -63.086234)
		(property "Reference" "R5843"
			(at 0 0 0)
			(layer "F.SilkS")
			(hide yes)
			(effects
				(font
					(size 1.27 1.27)
				)
			)
		)
		(property "Value" ""
			(at 0 0 0)
			(layer "F.Fab")
			(effects
				(font
					(size 1.27 1.27)
				)
			)
		)
		(duplicate_pad_numbers_are_jumpers no)
		(fp_line
			(start -0.7874 -0.4064)
			(end 0.7874 -0.4064)
			(stroke
				(width 0.1524)
				(type default)
			)
			(layer "F.SilkS")
		)
		(fp_line
			(start -0.7874 0.4064)
			(end -0.7874 -0.4064)
			(stroke
				(width 0.1524)
				(type default)
			)
			(layer "F.SilkS")
		)
		(fp_line
			(start 0.7874 -0.4064)
			(end 0.7874 0.4064)
			(stroke
				(width 0.1524)
				(type default)
			)
			(layer "F.SilkS")
		)
		(fp_line
			(start 0.7874 0.4064)
			(end -0.7874 0.4064)
			(stroke
				(width 0.1524)
				(type default)
			)
			(layer "F.SilkS")
		)
		(fp_line
			(start -0.67945 -0.305054)
			(end -0.12065 -0.305054)
			(stroke
				(width 0.1)
				(type default)
			)
			(layer "F.Fab")
		)
		(fp_line
			(start -0.67945 0.3048)
			(end -0.67945 -0.305054)
			(stroke
				(width 0.1)
				(type default)
			)
			(layer "F.Fab")
		)
		(fp_line
			(start -0.12065 -0.305054)
			(end -0.12065 -0.2794)
			(stroke
				(width 0.1)
				(type default)
			)
			(layer "F.Fab")
		)
		(fp_line
			(start -0.12065 -0.2794)
			(end 0.12065 -0.2794)
			(stroke
				(width 0.1)
				(type default)
			)
			(layer "F.Fab")
		)
		(fp_line
			(start -0.12065 0.2794)
			(end -0.12065 0.3048)
			(stroke
				(width 0.1)
				(type default)
			)
			(layer "F.Fab")
		)
		(fp_line
			(start -0.12065 0.3048)
			(end -0.67945 0.3048)
			(stroke
				(width 0.1)
				(type default)
			)
			(layer "F.Fab")
		)
		(fp_line
			(start 0.120396 0.2794)
			(end -0.12065 0.2794)
			(stroke
				(width 0.1)
				(type default)
			)
			(layer "F.Fab")
		)
		(fp_line
			(start 0.120396 0.3048)
			(end 0.120396 0.2794)
			(stroke
				(width 0.1)
				(type default)
			)
			(layer "F.Fab")
		)
		(fp_line
			(start 0.12065 -0.3048)
			(end 0.67945 -0.3048)
			(stroke
				(width 0.1)
				(type default)
			)
			(layer "F.Fab")
		)
		(fp_line
			(start 0.12065 -0.2794)
			(end 0.12065 -0.3048)
			(stroke
				(width 0.1)
				(type default)
			)
			(layer "F.Fab")
		)
		(fp_line
			(start 0.67945 -0.3048)
			(end 0.67945 0.3048)
			(stroke
				(width 0.1)
				(type default)
			)
			(layer "F.Fab")
		)
		(fp_line
			(start 0.67945 0.3048)
			(end 0.120396 0.3048)
			(stroke
				(width 0.1)
				(type default)
			)
			(layer "F.Fab")
		)
		(pad "1" smd circle
			(at -0.40005 0)
			(size 0 0)
			(layers "F.Cu" "F.Mask" "F.Paste")
			(net "P12V_SSD1_R")
		)
		(pad "2" smd circle
			(at 0.40005 0)
			(size 0 0)
			(layers "F.Cu" "F.Mask" "F.Paste")
			(net "P12V_SSD1_PG_G1")
		)
	)
	(footprint ""
		(layer "F.Cu")
		(at 280.759154 -166.55288)
		(property "Reference" "U30"
			(at -1.8034 -1.819148 0)
			(unlocked yes)
			(layer "F.SilkS")
			(effects
				(font
					(size 0.7874 0.5842)
					(thickness 0.1524)
				)
				(justify left)
			)
		)
		(property "Value" ""
			(at 0 0 0)
			(layer "F.Fab")
			(effects
				(font
					(size 1.27 1.27)
				)
			)
		)
		(duplicate_pad_numbers_are_jumpers no)
		(fp_line
			(start -1.684274 -1.074928)
			(end -0.381 -1.074928)
			(stroke
				(width 0.1524)
				(type default)
			)
			(layer "F.SilkS")
		)
		(fp_line
			(start -1.684274 1.074928)
			(end -1.684274 -1.074928)
			(stroke
				(width 0.1524)
				(type default)
			)
			(layer "F.SilkS")
		)
		(fp_line
			(start -0.381 -1.074928)
			(end 0 -0.625094)
			(stroke
				(width 0.1524)
				(type default)
			)
			(layer "F.SilkS")
		)
		(fp_line
			(start 0 -0.625094)
			(end 0.381 -1.074928)
			(stroke
				(width 0.1524)
				(type default)
			)
			(layer "F.SilkS")
		)
		(fp_line
			(start 0.381 -1.074928)
			(end 1.684274 -1.074928)
			(stroke
				(width 0.1524)
				(type default)
			)
			(layer "F.SilkS")
		)
		(fp_line
			(start 1.684274 -1.074928)
			(end 1.684274 1.074928)
			(stroke
				(width 0.1524)
				(type default)
			)
			(layer "F.SilkS")
		)
		(fp_line
			(start 1.684274 1.074928)
			(end -1.684274 1.074928)
			(stroke
				(width 0.1524)
				(type default)
			)
			(layer "F.SilkS")
		)
		(fp_poly
			(pts
				(xy -2.637282 -0.903986) (xy -2.637282 -0.395986) (xy -1.875282 -0.649986)
			)
			(stroke
				(width 0)
				(type default)
			)
			(fill yes)
			(layer "F.SilkS")
		)
		(fp_line
			(start -0.700024 -1.074928)
			(end -0.700024 1.074928)
			(stroke
				(width 0.1)
				(type default)
			)
			(layer "F.Fab")
		)
		(fp_line
			(start -0.700024 1.074928)
			(end 0.700024 1.074928)
			(stroke
				(width 0.1)
				(type default)
			)
			(layer "F.Fab")
		)
		(fp_line
			(start 0.700024 -1.074928)
			(end -0.700024 -1.074928)
			(stroke
				(width 0.1)
				(type default)
			)
			(layer "F.Fab")
		)
		(fp_line
			(start 0.700024 1.074928)
			(end 0.700024 -1.074928)
			(stroke
				(width 0.1)
				(type default)
			)
			(layer "F.Fab")
		)
		(fp_poly
			(pts
				(xy -2.637282 -0.903986) (xy -2.637282 -0.395986) (xy -1.875282 -0.649986)
			)
			(stroke
				(width 0)
				(type default)
			)
			(fill yes)
			(layer "F.Fab")
		)
		(pad "1" smd rect
			(at -1.100074 -0.649986 270)
			(size 0.4064 0.9144)
			(layers "F.Cu" "F.Mask" "F.Paste")
			(net "Net_8452")
		)
		(pad "2" smd rect
			(at -1.100074 0 270)
			(size 0.4064 0.9144)
			(layers "F.Cu" "F.Mask" "F.Paste")
			(net "RST_HP_NIC4_N")
		)
		(pad "3" smd rect
			(at -1.100074 0.649986 270)
			(size 0.4064 0.9144)
			(layers "F.Cu" "F.Mask" "F.Paste")
			(net "GND")
		)
		(pad "4" smd rect
			(at 1.100074 0.649986 270)
			(size 0.4064 0.9144)
			(layers "F.Cu" "F.Mask" "F.Paste")
			(net "RST_HP_NIC4_BUF_N")
		)
		(pad "5" smd rect
			(at 1.100074 -0.649986 270)
			(size 0.4064 0.9144)
			(layers "F.Cu" "F.Mask" "F.Paste")
			(net "P3V3_AUX")
		)
	)
	(footprint ""
		(layer "F.Cu")
		(at 28.856178 -32.848042 -90)
		(property "Reference" "R5867"
			(at 0 0 270)
			(layer "F.SilkS")
			(hide yes)
			(effects
				(font
					(size 1.27 1.27)
				)
			)
		)
		(property "Value" ""
			(at 0 0 270)
			(layer "F.Fab")
			(effects
				(font
					(size 1.27 1.27)
				)
			)
		)
		(duplicate_pad_numbers_are_jumpers no)
		(fp_line
			(start -0.7874 0.4064)
			(end -0.7874 -0.4064)
			(stroke
				(width 0.1524)
				(type default)
			)
			(layer "F.SilkS")
		)
		(fp_line
			(start 0.7874 0.4064)
			(end -0.7874 0.4064)
			(stroke
				(width 0.1524)
				(type default)
			)
			(layer "F.SilkS")
		)
		(fp_line
			(start -0.7874 -0.4064)
			(end 0.7874 -0.4064)
			(stroke
				(width 0.1524)
				(type default)
			)
			(layer "F.SilkS")
		)
		(fp_line
			(start 0.7874 -0.4064)
			(end 0.7874 0.4064)
			(stroke
				(width 0.1524)
				(type default)
			)
			(layer "F.SilkS")
		)
		(fp_line
			(start -0.67945 0.3048)
			(end -0.67945 -0.305054)
			(stroke
				(width 0.1)
				(type default)
			)
			(layer "F.Fab")
		)
		(fp_line
			(start -0.12065 0.3048)
			(end -0.67945 0.3048)
			(stroke
				(width 0.1)
				(type default)
			)
			(layer "F.Fab")
		)
		(fp_line
			(start 0.120396 0.3048)
			(end 0.120396 0.2794)
			(stroke
				(width 0.1)
				(type default)
			)
			(layer "F.Fab")
		)
		(fp_line
			(start 0.67945 0.3048)
			(end 0.120396 0.3048)
			(stroke
				(width 0.1)
				(type default)
			)
			(layer "F.Fab")
		)
		(fp_line
			(start -0.12065 0.2794)
			(end -0.12065 0.3048)
			(stroke
				(width 0.1)
				(type default)
			)
			(layer "F.Fab")
		)
		(fp_line
			(start 0.120396 0.2794)
			(end -0.12065 0.2794)
			(stroke
				(width 0.1)
				(type default)
			)
			(layer "F.Fab")
		)
		(fp_line
			(start -0.12065 -0.2794)
			(end 0.12065 -0.2794)
			(stroke
				(width 0.1)
				(type default)
			)
			(layer "F.Fab")
		)
		(fp_line
			(start 0.12065 -0.2794)
			(end 0.12065 -0.3048)
			(stroke
				(width 0.1)
				(type default)
			)
			(layer "F.Fab")
		)
		(fp_line
			(start 0.12065 -0.3048)
			(end 0.67945 -0.3048)
			(stroke
				(width 0.1)
				(type default)
			)
			(layer "F.Fab")
		)
		(fp_line
			(start 0.67945 -0.3048)
			(end 0.67945 0.3048)
			(stroke
				(width 0.1)
				(type default)
			)
			(layer "F.Fab")
		)
		(fp_line
			(start -0.67945 -0.305054)
			(end -0.12065 -0.305054)
			(stroke
				(width 0.1)
				(type default)
			)
			(layer "F.Fab")
		)
		(fp_line
			(start -0.12065 -0.305054)
			(end -0.12065 -0.2794)
			(stroke
				(width 0.1)
				(type default)
			)
			(layer "F.Fab")
		)
		(pad "1" smd circle
			(at -0.40005 0 270)
			(size 0 0)
			(layers "F.Cu" "F.Mask" "F.Paste")
			(net "SSD1_AUX_P3V3_EN_R")
		)
		(pad "2" smd circle
			(at 0.40005 0 270)
			(size 0 0)
			(layers "F.Cu" "F.Mask" "F.Paste")
			(net "P3V3_SSD1_CO_EN")
		)
	)
	(footprint ""
		(layer "F.Cu")
		(at 241.756692 -92.244164 90)
		(property "Reference" "Y5"
			(at 2.140966 -0.761492 0)
			(unlocked yes)
			(layer "F.SilkS")
			(effects
				(font
					(size 0.7874 0.5842)
					(thickness 0.1524)
				)
				(justify left)
			)
		)
		(property "Value" ""
			(at 0 0 90)
			(layer "F.Fab")
			(effects
				(font
					(size 1.27 1.27)
				)
			)
		)
		(duplicate_pad_numbers_are_jumpers no)
		(fp_line
			(start 1.2446 -1.4986)
			(end -1.2446 -1.4986)
			(stroke
				(width 0.1524)
				(type default)
			)
			(layer "F.SilkS")
		)
		(fp_line
			(start -1.2446 -1.4986)
			(end -1.2446 1.4986)
			(stroke
				(width 0.1524)
				(type default)
			)
			(layer "F.SilkS")
		)
		(fp_line
			(start 1.2446 1.4986)
			(end 1.2446 -1.4986)
			(stroke
				(width 0.1524)
				(type default)
			)
			(layer "F.SilkS")
		)
		(fp_line
			(start -1.2446 1.4986)
			(end 1.2446 1.4986)
			(stroke
				(width 0.1524)
				(type default)
			)
			(layer "F.SilkS")
		)
		(fp_poly
			(pts
				(xy -2.4638 -1.357884) (xy -2.4638 -0.341884) (xy -1.4478 -0.849884)
			)
			(stroke
				(width 0)
				(type default)
			)
			(fill yes)
			(layer "F.SilkS")
		)
		(fp_line
			(start 1.050036 -1.299972)
			(end -1.050036 -1.299972)
			(stroke
				(width 0.1)
				(type default)
			)
			(layer "F.Fab")
		)
		(fp_line
			(start -1.050036 -1.299972)
			(end -1.050036 1.299972)
			(stroke
				(width 0.1)
				(type default)
			)
			(layer "F.Fab")
		)
		(fp_line
			(start 1.050036 1.299972)
			(end 1.050036 -1.299972)
			(stroke
				(width 0.1)
				(type default)
			)
			(layer "F.Fab")
		)
		(fp_line
			(start -1.050036 1.299972)
			(end 1.050036 1.299972)
			(stroke
				(width 0.1)
				(type default)
			)
			(layer "F.Fab")
		)
		(fp_poly
			(pts
				(xy -2.4638 -1.357884) (xy -2.4638 -0.341884) (xy -1.4478 -0.849884)
			)
			(stroke
				(width 0)
				(type default)
			)
			(fill yes)
			(layer "F.Fab")
		)
		(pad "1" smd rect
			(at -0.649986 -0.849884 270)
			(size 0.9144 1.016)
			(layers "F.Cu" "F.Mask" "F.Paste")
			(net "PEX_USB_HUB_XIN")
		)
		(pad "2" smd rect
			(at -0.649986 0.849884 270)
			(size 0.9144 1.016)
			(layers "F.Cu" "F.Mask" "F.Paste")
			(net "GND")
		)
		(pad "3" smd rect
			(at 0.649986 0.849884 270)
			(size 0.9144 1.016)
			(layers "F.Cu" "F.Mask" "F.Paste")
			(net "PEX_USB_HUB_XOUT_R")
		)
		(pad "4" smd rect
			(at 0.649986 -0.849884 270)
			(size 0.9144 1.016)
			(layers "F.Cu" "F.Mask" "F.Paste")
			(net "GND")
		)
	)
)
